# BASEBOARD_FAB2 (Tioga Pass) — schematic netlist excerpt (pin names and nets, part order shuffled) for the footprints in the layout excerpt that follows; sources: Cadence DE-HDL packaged netlist, KiCad conversion of Wiwynn_Tioga_Pass_MB.brd

C5U2  CAP_A  47UF 4V 20% X5R  pkg 0603V  page 217 : A = PVDDQ_ABC ; B = GND
C7U6  CAP  10UF 4V 20% X6S  pkg 0603LF  page 233 : A = PVPP_GHJ ; B = GND
C1M16  CAP  0.22UF 16V 10% X7R  pkg 0402  page 106 : A = P3E_CPU0_PE3_OCP_TXP<10> ; B = P3E_OCP_CPU0_PE3_C_TXP<10>

(kicad_pcb
	(version 20260206)
	(generator "pcbnew")
	(generator_version "10.0")
	(general
		(thickness 1.6)
		(legacy_teardrops no)
	)
	(paper "A4")
	(title_block
		(title "Wiwynn_Tioga_Pass_MB.brd")
		(comment 1 "Tioga Pass / footprints 4651-4653 of 4770")
	)
	(layers
		(0 "F.Cu" signal "TOP")
		(4 "In1.Cu" signal "L2GND")
		(6 "In2.Cu" signal "L3")
		(8 "In3.Cu" signal "L4GND")
		(10 "In4.Cu" signal "L5")
		(12 "In5.Cu" signal "L6GND")
		(14 "In6.Cu" signal "L7VCC")
		(16 "In7.Cu" signal "L8VCC")
		(18 "In8.Cu" signal "L9GND")
		(20 "In9.Cu" signal "L10")
		(22 "In10.Cu" signal "L11GND")
		(24 "In11.Cu" signal "L12")
		(26 "In12.Cu" signal "L13GND")
		(2 "B.Cu" signal "BOTTOM")
		(9 "F.Adhes" user "F.Adhesive")
		(11 "B.Adhes" user "B.Adhesive")
		(13 "F.Paste" user "Package Geometry/Pastemask Top")
		(15 "B.Paste" user "Package Geometry/Pastemask Bottom")
		(5 "F.SilkS" user "Ref Des/Silkscreen Top")
		(7 "B.SilkS" user "Ref Des/Silkscreen Bottom")
		(1 "F.Mask" user "Board Geometry/Soldermask Top")
		(3 "B.Mask" user "Board Geometry/Soldermask Bottom")
		(17 "Dwgs.User" user "User.Drawings")
		(19 "Cmts.User" user "User.Comments")
		(21 "Eco1.User" user "User.Eco1")
		(23 "Eco2.User" user "User.Eco2")
		(25 "Edge.Cuts" user "Board Geometry/Outline")
		(27 "Margin" user)
		(31 "F.CrtYd" user "Package Geometry/Place Bound Top")
		(29 "B.CrtYd" user "Package Geometry/Place Bound Bottom")
		(35 "F.Fab" user "Ref Des/Assembly Top")
		(33 "B.Fab" user "Ref Des/Assembly Bottom")
	)
	(footprint ""
		(layer "B.Cu")
		(at 276.000464 -8.1534 90)
		(property "Reference" "C5U2"
			(at -1.848866 0.752348 90)
			(unlocked yes)
			(layer "B.SilkS")
			(effects
				(font
					(size 1.27 0.9652)
					(thickness 0.1524)
				)
				(justify mirror)
			)
		)
		(property "Value" ""
			(at 0 0 90)
			(layer "B.Fab")
			(effects
				(font
					(size 1.27 1.27)
				)
				(justify mirror)
			)
		)
		(duplicate_pad_numbers_are_jumpers no)
		(fp_rect
			(start 0.500126 1.598422)
			(end -0.500126 -0.201422)
			(stroke
				(width 0)
				(type default)
			)
			(fill no)
			(layer "B.CrtYd")
		)
		(fp_line
			(start 0.500126 -0.201422)
			(end -0.500126 -0.201422)
			(stroke
				(width 0.1)
				(type default)
			)
			(layer "B.Fab")
		)
		(fp_line
			(start -0.500126 -0.201422)
			(end -0.500126 1.598422)
			(stroke
				(width 0.1)
				(type default)
			)
			(layer "B.Fab")
		)
		(fp_line
			(start 0.500126 1.598422)
			(end 0.500126 -0.201422)
			(stroke
				(width 0.1)
				(type default)
			)
			(layer "B.Fab")
		)
		(fp_line
			(start -0.500126 1.598422)
			(end 0.500126 1.598422)
			(stroke
				(width 0.1)
				(type default)
			)
			(layer "B.Fab")
		)
		(pad "1" smd rect
			(at 0 0)
			(size 0.889 0.9906)
			(layers "B.Cu" "B.Mask" "B.Paste")
			(net "PVDDQ_ABC")
		)
		(pad "2" smd rect
			(at 0 1.397)
			(size 0.889 0.9906)
			(layers "B.Cu" "B.Mask" "B.Paste")
			(net "GND")
		)
		(zone
			(layer "B.Cu")
			(hatch none 0.5)
			(connect_pads
				(clearance 0)
			)
			(min_thickness 0.25)
			(keepout
				(tracks allowed)
				(vias not_allowed)
				(pads allowed)
				(copperpour not_allowed)
				(footprints allowed)
			)
			(placement
				(enabled no)
				(sheetname "")
			)
			(fill
				(thermal_gap 0.5)
				(thermal_bridge_width 0.5)
				(island_removal_mode 0)
			)
			(polygon
				(pts
					(xy 276.952964 -8.6487) (xy 276.444964 -8.6487) (xy 276.444964 -7.6581) (xy 276.952964 -7.6581)
				)
			)
		)
		(zone
			(layer "B.Cu")
			(hatch none 0.5)
			(connect_pads
				(clearance 0)
			)
			(min_thickness 0.25)
			(keepout
				(tracks not_allowed)
				(vias allowed)
				(pads allowed)
				(copperpour not_allowed)
				(footprints allowed)
			)
			(placement
				(enabled no)
				(sheetname "")
			)
			(fill
				(thermal_gap 0.5)
				(thermal_bridge_width 0.5)
				(island_removal_mode 0)
			)
			(polygon
				(pts
					(xy 276.952964 -8.6487) (xy 276.444964 -8.6487) (xy 276.444964 -7.6581) (xy 276.952964 -7.6581)
				)
			)
		)
	)
	(footprint ""
		(layer "B.Cu")
		(at 153.797 1.7018 -90)
		(property "Reference" "C7U6"
			(at 0 0 90)
			(layer "B.SilkS")
			(hide yes)
			(effects
				(font
					(size 1.27 1.27)
				)
				(justify mirror)
			)
		)
		(property "Value" ""
			(at 0 0 90)
			(layer "B.Fab")
			(effects
				(font
					(size 1.27 1.27)
				)
				(justify mirror)
			)
		)
		(duplicate_pad_numbers_are_jumpers no)
		(fp_poly
			(pts
				(xy 0.4953 -0.2032) (xy -0.4953 -0.2032) (xy -0.4953 1.6002) (xy 0.4953 1.6002)
			)
			(stroke
				(width 0)
				(type default)
			)
			(fill no)
			(layer "B.CrtYd")
		)
		(fp_line
			(start -0.4953 1.6002)
			(end 0.4953 1.6002)
			(stroke
				(width 0.1)
				(type default)
			)
			(layer "B.Fab")
		)
		(fp_line
			(start 0.4953 1.6002)
			(end 0.4953 -0.2032)
			(stroke
				(width 0.1)
				(type default)
			)
			(layer "B.Fab")
		)
		(fp_line
			(start -0.4953 -0.2032)
			(end -0.4953 1.6002)
			(stroke
				(width 0.1)
				(type default)
			)
			(layer "B.Fab")
		)
		(fp_line
			(start 0.4953 -0.2032)
			(end -0.4953 -0.2032)
			(stroke
				(width 0.1)
				(type default)
			)
			(layer "B.Fab")
		)
		(pad "1" smd rect
			(at 0 0 90)
			(size 0.762 0.889)
			(layers "B.Cu" "B.Mask" "B.Paste")
			(net "PVPP_GHJ")
		)
		(pad "2" smd rect
			(at 0 1.397 90)
			(size 0.762 0.889)
			(layers "B.Cu" "B.Mask" "B.Paste")
			(net "GND")
		)
		(zone
			(layer "B.Cu")
			(hatch none 0.5)
			(connect_pads
				(clearance 0)
			)
			(min_thickness 0.25)
			(keepout
				(tracks not_allowed)
				(vias allowed)
				(pads allowed)
				(copperpour not_allowed)
				(footprints allowed)
			)
			(placement
				(enabled no)
				(sheetname "")
			)
			(fill
				(thermal_gap 0.5)
				(thermal_bridge_width 0.5)
				(island_removal_mode 0)
			)
			(polygon
				(pts
					(xy 153.3525 2.0828) (xy 153.3525 1.3208) (xy 152.8445 1.3208) (xy 152.8445 2.0828)
				)
			)
		)
	)
	(footprint ""
		(layer "B.Cu")
		(at 450.215 -116.49202)
		(property "Reference" "C1M16"
			(at 0 0 0)
			(layer "B.SilkS")
			(hide yes)
			(effects
				(font
					(size 1.27 1.27)
				)
				(justify mirror)
			)
		)
		(property "Value" ""
			(at 0 0 0)
			(layer "B.Fab")
			(effects
				(font
					(size 1.27 1.27)
				)
				(justify mirror)
			)
		)
		(duplicate_pad_numbers_are_jumpers no)
		(fp_rect
			(start -0.3048 0.9906)
			(end 0.3048 -0.1016)
			(stroke
				(width 0)
				(type default)
			)
			(fill no)
			(layer "B.CrtYd")
		)
		(fp_line
			(start -0.3048 -0.1016)
			(end 0.3048 -0.1016)
			(stroke
				(width 0.1)
				(type default)
			)
			(layer "B.Fab")
		)
		(fp_line
			(start -0.3048 0.9906)
			(end -0.3048 -0.1016)
			(stroke
				(width 0.1)
				(type default)
			)
			(layer "B.Fab")
		)
		(fp_line
			(start 0.3048 -0.1016)
			(end 0.3048 0.9906)
			(stroke
				(width 0.1)
				(type default)
			)
			(layer "B.Fab")
		)
		(fp_line
			(start 0.3048 0.9906)
			(end -0.3048 0.9906)
			(stroke
				(width 0.1)
				(type default)
			)
			(layer "B.Fab")
		)
		(pad "1" smd rect
			(at 0 0 180)
			(size 0.508 0.508)
			(layers "B.Cu" "B.Mask" "B.Paste")
			(net "P3E_CPU0_PE3_OCP_TXP<10>")
		)
		(pad "2" smd rect
			(at 0 0.889 180)
			(size 0.508 0.508)
			(layers "B.Cu" "B.Mask" "B.Paste")
			(net "P3E_OCP_CPU0_PE3_C_TXP<10>")
		)
		(zone
			(layer "B.Cu")
			(hatch none 0.5)
			(connect_pads
				(clearance 0)
			)
			(min_thickness 0.25)
			(keepout
				(tracks not_allowed)
				(vias allowed)
				(pads allowed)
				(copperpour not_allowed)
				(footprints allowed)
			)
			(placement
				(enabled no)
				(sheetname "")
			)
			(fill
				(thermal_gap 0.5)
				(thermal_bridge_width 0.5)
				(island_removal_mode 0)
			)
			(polygon
				(pts
					(xy 449.961 -115.85702) (xy 450.469 -115.85702) (xy 450.469 -116.23802) (xy 449.961 -116.23802)
				)
			)
		)
		(zone
			(layer "B.Cu")
			(hatch none 0.5)
			(connect_pads
				(clearance 0)
			)
			(min_thickness 0.25)
			(keepout
				(tracks allowed)
				(vias not_allowed)
				(pads allowed)
				(copperpour not_allowed)
				(footprints allowed)
			)
			(placement
				(enabled no)
				(sheetname "")
			)
			(fill
				(thermal_gap 0.5)
				(thermal_bridge_width 0.5)
				(island_removal_mode 0)
			)
			(polygon
				(pts
					(xy 449.961 -115.85702) (xy 450.469 -115.85702) (xy 450.469 -116.23802) (xy 449.961 -116.23802)
				)
			)
		)
	)
)
